# S9S_MB_2U (Grand Teton) — schematic netlist excerpt (pin names and nets, part order shuffled) for the footprints in the layout excerpt that follows; sources: Cadence DE-HDL packaged netlist, KiCad conversion of 03242023_DA0F0TMBIJ0_F0T_Motherboard_J_brd_V01_OCP.brd

C1897  Q_CAP  0.01UF 50V 10% X7R  pkg C0402  page 217 : A = VCC_PLD_CORE ; B = GND
PC608_P0_1  Q_CAP  22UF 16V 20% X6S  pkg C0805  page 271 : A = SW_P12V_PVCCFA_EHV_FIVRA_CPU0_R ; B = GND
PC411_P1_2  Q_CAP  22UF 4V 20% X6S  pkg C0805  page 289 : A = PVCCFA_EHV_FIVRA_CPU1 ; B = GND

(kicad_pcb
	(version 20260206)
	(generator "pcbnew")
	(generator_version "10.0")
	(general
		(thickness 1.6)
		(legacy_teardrops no)
	)
	(paper "A4")
	(title_block
		(title "03242023_DA0F0TMBIJ0_F0T_Motherboard_J_brd_V01_OCP.brd")
		(comment 1 "Grand Teton / footprints 5061-5063 of 6105")
	)
	(layers
		(0 "F.Cu" signal "TOP")
		(4 "In1.Cu" signal "GND")
		(6 "In2.Cu" signal "IN1")
		(8 "In3.Cu" signal "GND1")
		(10 "In4.Cu" signal "IN2")
		(12 "In5.Cu" signal "GND2")
		(14 "In6.Cu" signal "IN3")
		(16 "In7.Cu" signal "GND3")
		(18 "In8.Cu" signal "VCC")
		(20 "In9.Cu" signal "VCC1")
		(22 "In10.Cu" signal "GND4")
		(24 "In11.Cu" signal "IN4")
		(26 "In12.Cu" signal "GND5")
		(28 "In13.Cu" signal "IN5")
		(30 "In14.Cu" signal "GND6")
		(32 "In15.Cu" signal "IN6")
		(34 "In16.Cu" signal "GND7")
		(2 "B.Cu" signal "BOTTOM")
		(9 "F.Adhes" user "F.Adhesive")
		(11 "B.Adhes" user "B.Adhesive")
		(13 "F.Paste" user "Package Geometry/Pastemask Top")
		(15 "B.Paste" user "Package Geometry/Pastemask Bottom")
		(5 "F.SilkS" user "Ref Des/Silkscreen Top")
		(7 "B.SilkS" user "Ref Des/Silkscreen Bottom")
		(1 "F.Mask" user "Board Geometry/Soldermask Top")
		(3 "B.Mask" user "Board Geometry/Soldermask Bottom")
		(17 "Dwgs.User" user "User.Drawings")
		(19 "Cmts.User" user "User.Comments")
		(21 "Eco1.User" user "User.Eco1")
		(23 "Eco2.User" user "User.Eco2")
		(25 "Edge.Cuts" user "Board Geometry/Outline")
		(27 "Margin" user)
		(31 "F.CrtYd" user "Package Geometry/Place Bound Top")
		(29 "B.CrtYd" user "Package Geometry/Place Bound Bottom")
		(35 "F.Fab" user "Ref Des/Assembly Top")
		(33 "B.Fab" user "Ref Des/Assembly Bottom")
	)
	(footprint ""
		(layer "B.Cu")
		(at 419.417246 -362.107226 90)
		(property "Reference" "PC608_P0_1"
			(at 0 0 90)
			(layer "B.SilkS")
			(hide yes)
			(effects
				(font
					(size 1.27 1.27)
				)
				(justify mirror)
			)
		)
		(property "Value" ""
			(at 0 0 90)
			(layer "B.Fab")
			(effects
				(font
					(size 1.27 1.27)
				)
				(justify mirror)
			)
		)
		(duplicate_pad_numbers_are_jumpers no)
		(fp_line
			(start 1.524 -0.762)
			(end -1.524 -0.762)
			(stroke
				(width 0.1524)
				(type default)
			)
			(layer "B.SilkS")
		)
		(fp_line
			(start -1.524 -0.762)
			(end -1.524 0.762)
			(stroke
				(width 0.1524)
				(type default)
			)
			(layer "B.SilkS")
		)
		(fp_line
			(start 1.524 0.762)
			(end 1.524 -0.762)
			(stroke
				(width 0.1524)
				(type default)
			)
			(layer "B.SilkS")
		)
		(fp_line
			(start -1.524 0.762)
			(end 1.524 0.762)
			(stroke
				(width 0.1524)
				(type default)
			)
			(layer "B.SilkS")
		)
		(fp_line
			(start 1.1049 -0.724916)
			(end 1.1049 0.724916)
			(stroke
				(width 0.1)
				(type default)
			)
			(layer "B.Fab")
		)
		(fp_line
			(start -1.1049 -0.724916)
			(end 1.1049 -0.724916)
			(stroke
				(width 0.1)
				(type default)
			)
			(layer "B.Fab")
		)
		(fp_line
			(start 1.1049 0.724916)
			(end -1.1049 0.724916)
			(stroke
				(width 0.1)
				(type default)
			)
			(layer "B.Fab")
		)
		(fp_line
			(start -1.1049 0.724916)
			(end -1.1049 -0.724916)
			(stroke
				(width 0.1)
				(type default)
			)
			(layer "B.Fab")
		)
		(pad "1" smd rect
			(at 0.889 0 90)
			(size 1.016 1.27)
			(layers "B.Cu" "B.Mask" "B.Paste")
			(net "SW_P12V_PVCCFA_EHV_FIVRA_CPU0_R")
		)
		(pad "2" smd rect
			(at -0.889 0 90)
			(size 1.016 1.27)
			(layers "B.Cu" "B.Mask" "B.Paste")
			(net "GND")
		)
	)
	(footprint ""
		(layer "B.Cu")
		(at 55.87492 -344.650314 -90)
		(property "Reference" "PC411_P1_2"
			(at 0 0 90)
			(layer "B.SilkS")
			(hide yes)
			(effects
				(font
					(size 1.27 1.27)
				)
				(justify mirror)
			)
		)
		(property "Value" ""
			(at 0 0 90)
			(layer "B.Fab")
			(effects
				(font
					(size 1.27 1.27)
				)
				(justify mirror)
			)
		)
		(duplicate_pad_numbers_are_jumpers no)
		(fp_line
			(start -1.524 0.762)
			(end 1.524 0.762)
			(stroke
				(width 0.1524)
				(type default)
			)
			(layer "B.SilkS")
		)
		(fp_line
			(start 1.524 0.762)
			(end 1.524 -0.762)
			(stroke
				(width 0.1524)
				(type default)
			)
			(layer "B.SilkS")
		)
		(fp_line
			(start -1.524 -0.762)
			(end -1.524 0.762)
			(stroke
				(width 0.1524)
				(type default)
			)
			(layer "B.SilkS")
		)
		(fp_line
			(start 1.524 -0.762)
			(end -1.524 -0.762)
			(stroke
				(width 0.1524)
				(type default)
			)
			(layer "B.SilkS")
		)
		(fp_line
			(start -1.1049 0.724916)
			(end -1.1049 -0.724916)
			(stroke
				(width 0.1)
				(type default)
			)
			(layer "B.Fab")
		)
		(fp_line
			(start 1.1049 0.724916)
			(end -1.1049 0.724916)
			(stroke
				(width 0.1)
				(type default)
			)
			(layer "B.Fab")
		)
		(fp_line
			(start -1.1049 -0.724916)
			(end 1.1049 -0.724916)
			(stroke
				(width 0.1)
				(type default)
			)
			(layer "B.Fab")
		)
		(fp_line
			(start 1.1049 -0.724916)
			(end 1.1049 0.724916)
			(stroke
				(width 0.1)
				(type default)
			)
			(layer "B.Fab")
		)
		(pad "1" smd rect
			(at 0.889 0 270)
			(size 1.016 1.27)
			(layers "B.Cu" "B.Mask" "B.Paste")
			(net "PVCCFA_EHV_FIVRA_CPU1")
		)
		(pad "2" smd rect
			(at -0.889 0 270)
			(size 1.016 1.27)
			(layers "B.Cu" "B.Mask" "B.Paste")
			(net "GND")
		)
	)
	(footprint ""
		(layer "B.Cu")
		(at 180.155596 -113.77549 180)
		(property "Reference" "C1897"
			(at 0 0 0)
			(layer "B.SilkS")
			(hide yes)
			(effects
				(font
					(size 1.27 1.27)
				)
				(justify mirror)
			)
		)
		(property "Value" ""
			(at 0 0 0)
			(layer "B.Fab")
			(effects
				(font
					(size 1.27 1.27)
				)
				(justify mirror)
			)
		)
		(duplicate_pad_numbers_are_jumpers no)
		(fp_line
			(start 0.69215 0.2921)
			(end 0.69215 -0.2921)
			(stroke
				(width 0.1524)
				(type default)
			)
			(layer "B.SilkS")
		)
		(fp_line
			(start 0.69215 -0.2921)
			(end -0.69215 -0.2921)
			(stroke
				(width 0.1524)
				(type default)
			)
			(layer "B.SilkS")
		)
		(fp_line
			(start -0.69215 0.2921)
			(end 0.69215 0.2921)
			(stroke
				(width 0.1524)
				(type default)
			)
			(layer "B.SilkS")
		)
		(fp_line
			(start -0.69215 -0.2921)
			(end -0.69215 0.2921)
			(stroke
				(width 0.1524)
				(type default)
			)
			(layer "B.SilkS")
		)
		(fp_line
			(start 0.51435 0.2794)
			(end 0.51435 -0.2794)
			(stroke
				(width 0.1)
				(type default)
			)
			(layer "B.Fab")
		)
		(fp_line
			(start 0.51435 -0.2794)
			(end -0.51435 -0.2794)
			(stroke
				(width 0.1)
				(type default)
			)
			(layer "B.Fab")
		)
		(fp_line
			(start -0.51435 0.2794)
			(end 0.51435 0.2794)
			(stroke
				(width 0.1)
				(type default)
			)
			(layer "B.Fab")
		)
		(fp_line
			(start -0.51435 -0.2794)
			(end -0.51435 0.2794)
			(stroke
				(width 0.1)
				(type default)
			)
			(layer "B.Fab")
		)
		(pad "1" smd circle
			(at 0.40005 0)
			(size 0 0)
			(layers "B.Cu" "B.Mask" "B.Paste")
			(net "VCC_PLD_CORE")
		)
		(pad "2" smd circle
			(at -0.40005 0)
			(size 0 0)
			(layers "B.Cu" "B.Mask" "B.Paste")
			(net "GND")
		)
		(zone
			(layer "B.Cu")
			(hatch none 0.5)
			(connect_pads
				(clearance 0)
			)
			(min_thickness 0.25)
			(keepout
				(tracks not_allowed)
				(vias allowed)
				(pads allowed)
				(copperpour not_allowed)
				(footprints allowed)
			)
			(placement
				(enabled no)
				(sheetname "")
			)
			(fill
				(thermal_gap 0.5)
				(thermal_bridge_width 0.5)
				(island_removal_mode 0)
			)
			(polygon
				(pts
					(xy 179.965096 -113.86312) (xy 180.056536 -113.921286) (xy 180.255926 -113.921286) (xy 180.346096 -113.86312)
					(xy 180.346096 -113.68786) (xy 180.255926 -113.62944) (xy 180.056536 -113.62944) (xy 179.965096 -113.687606)
				)
			)
		)
	)
)
